# T6G (Grand Teton) — schematic netlist excerpt (pin names and nets, part order shuffled) for the footprints in the layout excerpt that follows; sources: Cadence DE-HDL packaged netlist, KiCad conversion of 04192023_DAF0TMB3IC0_F0TG_MB_C_brd_V02_OCP.brd

PR2536  Q_RES  10 1% CHIP  pkg 0402LF  page 266 : A = P12V_HSC_GATE_G6 ; B = P12V_HSC_GATE2
R1641  Q_RES  22 1% CHIP  pkg 0402LF  page 173 : A = JTAG_P0_R_DBREQ_N ; B = JTAG_CPU0_DBREQ_N

(kicad_pcb
	(version 20260206)
	(generator "pcbnew")
	(generator_version "10.0")
	(general
		(thickness 1.6)
		(legacy_teardrops no)
	)
	(paper "A4")
	(title_block
		(title "04192023_DAF0TMB3IC0_F0TG_MB_C_brd_V02_OCP.brd")
		(comment 1 "Grand Teton / footprints 2110-2111 of 8354")
	)
	(layers
		(0 "F.Cu" signal "TOP")
		(4 "In1.Cu" signal "GND")
		(6 "In2.Cu" signal "IN1")
		(8 "In3.Cu" signal "GND1")
		(10 "In4.Cu" signal "IN2")
		(12 "In5.Cu" signal "GND2")
		(14 "In6.Cu" signal "IN3")
		(16 "In7.Cu" signal "GND3")
		(18 "In8.Cu" signal "VCC")
		(20 "In9.Cu" signal "VCC1")
		(22 "In10.Cu" signal "GND4")
		(24 "In11.Cu" signal "IN4")
		(26 "In12.Cu" signal "GND5")
		(28 "In13.Cu" signal "IN5")
		(30 "In14.Cu" signal "GND6")
		(32 "In15.Cu" signal "IN6")
		(34 "In16.Cu" signal "GND7")
		(2 "B.Cu" signal "BOTTOM")
		(9 "F.Adhes" user "F.Adhesive")
		(11 "B.Adhes" user "B.Adhesive")
		(13 "F.Paste" user "Package Geometry/Pastemask Top")
		(15 "B.Paste" user "Package Geometry/Pastemask Bottom")
		(5 "F.SilkS" user "Ref Des/Silkscreen Top")
		(7 "B.SilkS" user "Ref Des/Silkscreen Bottom")
		(1 "F.Mask" user "Board Geometry/Soldermask Top")
		(3 "B.Mask" user "Board Geometry/Soldermask Bottom")
		(17 "Dwgs.User" user "User.Drawings")
		(19 "Cmts.User" user "User.Comments")
		(21 "Eco1.User" user "User.Eco1")
		(23 "Eco2.User" user "User.Eco2")
		(25 "Edge.Cuts" user "Board Geometry/Outline")
		(27 "Margin" user)
		(31 "F.CrtYd" user "Package Geometry/Place Bound Top")
		(29 "B.CrtYd" user "Package Geometry/Place Bound Bottom")
		(35 "F.Fab" user "Ref Des/Assembly Top")
		(33 "B.Fab" user "Ref Des/Assembly Bottom")
	)
	(footprint ""
		(layer "F.Cu")
		(at 251.06884 -92.719144 -90)
		(property "Reference" "R1641"
			(at 0 0 270)
			(layer "F.SilkS")
			(hide yes)
			(effects
				(font
					(size 1.27 1.27)
				)
			)
		)
		(property "Value" ""
			(at 0 0 270)
			(layer "F.Fab")
			(effects
				(font
					(size 1.27 1.27)
				)
			)
		)
		(duplicate_pad_numbers_are_jumpers no)
		(fp_line
			(start -0.7874 0.4064)
			(end -0.7874 -0.4064)
			(stroke
				(width 0.1524)
				(type default)
			)
			(layer "F.SilkS")
		)
		(fp_line
			(start 0.7874 0.4064)
			(end -0.7874 0.4064)
			(stroke
				(width 0.1524)
				(type default)
			)
			(layer "F.SilkS")
		)
		(fp_line
			(start -0.7874 -0.4064)
			(end 0.7874 -0.4064)
			(stroke
				(width 0.1524)
				(type default)
			)
			(layer "F.SilkS")
		)
		(fp_line
			(start 0.7874 -0.4064)
			(end 0.7874 0.4064)
			(stroke
				(width 0.1524)
				(type default)
			)
			(layer "F.SilkS")
		)
		(fp_line
			(start -0.67945 0.3048)
			(end -0.67945 -0.305054)
			(stroke
				(width 0.1)
				(type default)
			)
			(layer "F.Fab")
		)
		(fp_line
			(start -0.12065 0.3048)
			(end -0.67945 0.3048)
			(stroke
				(width 0.1)
				(type default)
			)
			(layer "F.Fab")
		)
		(fp_line
			(start 0.120396 0.3048)
			(end 0.120396 0.2794)
			(stroke
				(width 0.1)
				(type default)
			)
			(layer "F.Fab")
		)
		(fp_line
			(start 0.67945 0.3048)
			(end 0.120396 0.3048)
			(stroke
				(width 0.1)
				(type default)
			)
			(layer "F.Fab")
		)
		(fp_line
			(start -0.12065 0.2794)
			(end -0.12065 0.3048)
			(stroke
				(width 0.1)
				(type default)
			)
			(layer "F.Fab")
		)
		(fp_line
			(start 0.120396 0.2794)
			(end -0.12065 0.2794)
			(stroke
				(width 0.1)
				(type default)
			)
			(layer "F.Fab")
		)
		(fp_line
			(start -0.12065 -0.2794)
			(end 0.12065 -0.2794)
			(stroke
				(width 0.1)
				(type default)
			)
			(layer "F.Fab")
		)
		(fp_line
			(start 0.12065 -0.2794)
			(end 0.12065 -0.3048)
			(stroke
				(width 0.1)
				(type default)
			)
			(layer "F.Fab")
		)
		(fp_line
			(start 0.12065 -0.3048)
			(end 0.67945 -0.3048)
			(stroke
				(width 0.1)
				(type default)
			)
			(layer "F.Fab")
		)
		(fp_line
			(start 0.67945 -0.3048)
			(end 0.67945 0.3048)
			(stroke
				(width 0.1)
				(type default)
			)
			(layer "F.Fab")
		)
		(fp_line
			(start -0.67945 -0.305054)
			(end -0.12065 -0.305054)
			(stroke
				(width 0.1)
				(type default)
			)
			(layer "F.Fab")
		)
		(fp_line
			(start -0.12065 -0.305054)
			(end -0.12065 -0.2794)
			(stroke
				(width 0.1)
				(type default)
			)
			(layer "F.Fab")
		)
		(pad "1" smd circle
			(at -0.40005 0 270)
			(size 0 0)
			(layers "F.Cu" "F.Mask" "F.Paste")
			(net "JTAG_P0_R_DBREQ_N")
		)
		(pad "2" smd circle
			(at 0.40005 0 270)
			(size 0 0)
			(layers "F.Cu" "F.Mask" "F.Paste")
			(net "JTAG_CPU0_DBREQ_N")
		)
	)
	(footprint ""
		(layer "F.Cu")
		(at 249.896122 -380.66853)
		(property "Reference" "PR2536"
			(at 0 0 0)
			(layer "F.SilkS")
			(hide yes)
			(effects
				(font
					(size 1.27 1.27)
				)
			)
		)
		(property "Value" ""
			(at 0 0 0)
			(layer "F.Fab")
			(effects
				(font
					(size 1.27 1.27)
				)
			)
		)
		(duplicate_pad_numbers_are_jumpers no)
		(fp_line
			(start -0.7874 -0.4064)
			(end 0.7874 -0.4064)
			(stroke
				(width 0.1524)
				(type default)
			)
			(layer "F.SilkS")
		)
		(fp_line
			(start -0.7874 0.4064)
			(end -0.7874 -0.4064)
			(stroke
				(width 0.1524)
				(type default)
			)
			(layer "F.SilkS")
		)
		(fp_line
			(start 0.7874 -0.4064)
			(end 0.7874 0.4064)
			(stroke
				(width 0.1524)
				(type default)
			)
			(layer "F.SilkS")
		)
		(fp_line
			(start 0.7874 0.4064)
			(end -0.7874 0.4064)
			(stroke
				(width 0.1524)
				(type default)
			)
			(layer "F.SilkS")
		)
		(fp_line
			(start -0.67945 -0.305054)
			(end -0.12065 -0.305054)
			(stroke
				(width 0.1)
				(type default)
			)
			(layer "F.Fab")
		)
		(fp_line
			(start -0.67945 0.3048)
			(end -0.67945 -0.305054)
			(stroke
				(width 0.1)
				(type default)
			)
			(layer "F.Fab")
		)
		(fp_line
			(start -0.12065 -0.305054)
			(end -0.12065 -0.2794)
			(stroke
				(width 0.1)
				(type default)
			)
			(layer "F.Fab")
		)
		(fp_line
			(start -0.12065 -0.2794)
			(end 0.12065 -0.2794)
			(stroke
				(width 0.1)
				(type default)
			)
			(layer "F.Fab")
		)
		(fp_line
			(start -0.12065 0.2794)
			(end -0.12065 0.3048)
			(stroke
				(width 0.1)
				(type default)
			)
			(layer "F.Fab")
		)
		(fp_line
			(start -0.12065 0.3048)
			(end -0.67945 0.3048)
			(stroke
				(width 0.1)
				(type default)
			)
			(layer "F.Fab")
		)
		(fp_line
			(start 0.120396 0.2794)
			(end -0.12065 0.2794)
			(stroke
				(width 0.1)
				(type default)
			)
			(layer "F.Fab")
		)
		(fp_line
			(start 0.120396 0.3048)
			(end 0.120396 0.2794)
			(stroke
				(width 0.1)
				(type default)
			)
			(layer "F.Fab")
		)
		(fp_line
			(start 0.12065 -0.3048)
			(end 0.67945 -0.3048)
			(stroke
				(width 0.1)
				(type default)
			)
			(layer "F.Fab")
		)
		(fp_line
			(start 0.12065 -0.2794)
			(end 0.12065 -0.3048)
			(stroke
				(width 0.1)
				(type default)
			)
			(layer "F.Fab")
		)
		(fp_line
			(start 0.67945 -0.3048)
			(end 0.67945 0.3048)
			(stroke
				(width 0.1)
				(type default)
			)
			(layer "F.Fab")
		)
		(fp_line
			(start 0.67945 0.3048)
			(end 0.120396 0.3048)
			(stroke
				(width 0.1)
				(type default)
			)
			(layer "F.Fab")
		)
		(pad "1" smd circle
			(at -0.40005 0)
			(size 0 0)
			(layers "F.Cu" "F.Mask" "F.Paste")
			(net "P12V_HSC_GATE_G6")
		)
		(pad "2" smd circle
			(at 0.40005 0)
			(size 0 0)
			(layers "F.Cu" "F.Mask" "F.Paste")
			(net "P12V_HSC_GATE2")
		)
	)
)
